# S9S_MB_2U (Grand Teton) — schematic netlist excerpt (pin names and nets, part order shuffled) for the footprints in the layout excerpt that follows; sources: Cadence DE-HDL packaged netlist, KiCad conversion of 03242023_DA0F0TMBIJ0_F0T_Motherboard_J_brd_V01_OCP.brd

R4166  Q_RES  4.7K 5% CHIP  pkg 0402LF  page 145 : A = P3V3_AUX ; B = GPU_3V3IO_RSVD3_N

U219  74LVC1G07GV  IC  pkg SC-74A_2-9X1-5  page 161
  NC1  = NC_U219_NC1
  A  = OCP_V3_2_WAKE_BUFF_R_N
  GND  = GND
  Y  = IRQ_LVC3_V3_2_WAKE_BUF_N
  VCC  = P3V3_AUX

(kicad_pcb
	(version 20260206)
	(generator "pcbnew")
	(generator_version "10.0")
	(general
		(thickness 1.6)
		(legacy_teardrops no)
	)
	(paper "A4")
	(title_block
		(title "03242023_DA0F0TMBIJ0_F0T_Motherboard_J_brd_V01_OCP.brd")
		(comment 1 "Grand Teton / footprints 775-776 of 6105")
	)
	(layers
		(0 "F.Cu" signal "TOP")
		(4 "In1.Cu" signal "GND")
		(6 "In2.Cu" signal "IN1")
		(8 "In3.Cu" signal "GND1")
		(10 "In4.Cu" signal "IN2")
		(12 "In5.Cu" signal "GND2")
		(14 "In6.Cu" signal "IN3")
		(16 "In7.Cu" signal "GND3")
		(18 "In8.Cu" signal "VCC")
		(20 "In9.Cu" signal "VCC1")
		(22 "In10.Cu" signal "GND4")
		(24 "In11.Cu" signal "IN4")
		(26 "In12.Cu" signal "GND5")
		(28 "In13.Cu" signal "IN5")
		(30 "In14.Cu" signal "GND6")
		(32 "In15.Cu" signal "IN6")
		(34 "In16.Cu" signal "GND7")
		(2 "B.Cu" signal "BOTTOM")
		(9 "F.Adhes" user "F.Adhesive")
		(11 "B.Adhes" user "B.Adhesive")
		(13 "F.Paste" user "Package Geometry/Pastemask Top")
		(15 "B.Paste" user "Package Geometry/Pastemask Bottom")
		(5 "F.SilkS" user "Ref Des/Silkscreen Top")
		(7 "B.SilkS" user "Ref Des/Silkscreen Bottom")
		(1 "F.Mask" user "Board Geometry/Soldermask Top")
		(3 "B.Mask" user "Board Geometry/Soldermask Bottom")
		(17 "Dwgs.User" user "User.Drawings")
		(19 "Cmts.User" user "User.Comments")
		(21 "Eco1.User" user "User.Eco1")
		(23 "Eco2.User" user "User.Eco2")
		(25 "Edge.Cuts" user "Board Geometry/Outline")
		(27 "Margin" user)
		(31 "F.CrtYd" user "Package Geometry/Place Bound Top")
		(29 "B.CrtYd" user "Package Geometry/Place Bound Bottom")
		(35 "F.Fab" user "Ref Des/Assembly Top")
		(33 "B.Fab" user "Ref Des/Assembly Bottom")
	)
	(footprint ""
		(layer "F.Cu")
		(at 275.323046 -15.093188)
		(property "Reference" "U219"
			(at -5.59308 0.464312 0)
			(unlocked yes)
			(layer "F.SilkS")
			(effects
				(font
					(size 0.7874 0.5842)
					(thickness 0.1524)
				)
				(justify left)
			)
		)
		(property "Value" ""
			(at 0 0 0)
			(layer "F.Fab")
			(effects
				(font
					(size 1.27 1.27)
				)
			)
		)
		(duplicate_pad_numbers_are_jumpers no)
		(fp_line
			(start -1.733296 -1.549908)
			(end -1.733296 1.549908)
			(stroke
				(width 0.1524)
				(type default)
			)
			(layer "F.SilkS")
		)
		(fp_line
			(start -1.733296 1.549908)
			(end 1.733296 1.549908)
			(stroke
				(width 0.1524)
				(type default)
			)
			(layer "F.SilkS")
		)
		(fp_line
			(start -0.660908 -1.549908)
			(end -1.733296 -1.549908)
			(stroke
				(width 0.1524)
				(type default)
			)
			(layer "F.SilkS")
		)
		(fp_line
			(start 0 -0.889)
			(end -0.660908 -1.549908)
			(stroke
				(width 0.1524)
				(type default)
			)
			(layer "F.SilkS")
		)
		(fp_line
			(start 0.660908 -1.549908)
			(end 0 -0.889)
			(stroke
				(width 0.1524)
				(type default)
			)
			(layer "F.SilkS")
		)
		(fp_line
			(start 1.733296 -1.549908)
			(end 0.660908 -1.549908)
			(stroke
				(width 0.1524)
				(type default)
			)
			(layer "F.SilkS")
		)
		(fp_line
			(start 1.733296 1.549908)
			(end 1.733296 -1.549908)
			(stroke
				(width 0.1524)
				(type default)
			)
			(layer "F.SilkS")
		)
		(fp_poly
			(pts
				(xy -2.4384 -1.20396) (xy -1.9304 -0.94996) (xy -2.4384 -0.69596)
			)
			(stroke
				(width 0)
				(type default)
			)
			(fill yes)
			(layer "F.SilkS")
		)
		(fp_line
			(start -0.849884 -1.549908)
			(end -0.849884 1.549908)
			(stroke
				(width 0.1)
				(type default)
			)
			(layer "F.Fab")
		)
		(fp_line
			(start -0.849884 1.549908)
			(end 0.849884 1.549908)
			(stroke
				(width 0.1)
				(type default)
			)
			(layer "F.Fab")
		)
		(fp_line
			(start 0.849884 -1.549908)
			(end -0.849884 -1.549908)
			(stroke
				(width 0.1)
				(type default)
			)
			(layer "F.Fab")
		)
		(fp_line
			(start 0.849884 1.549908)
			(end 0.849884 -1.549908)
			(stroke
				(width 0.1)
				(type default)
			)
			(layer "F.Fab")
		)
		(fp_poly
			(pts
				(xy -2.4384 -1.20396) (xy -2.4384 -0.69596) (xy -1.9304 -0.94996)
			)
			(stroke
				(width 0)
				(type default)
			)
			(fill yes)
			(layer "F.Fab")
		)
		(pad "1" smd rect
			(at -1.199896 -0.94996 270)
			(size 0.5588 0.8128)
			(layers "F.Cu" "F.Mask" "F.Paste")
			(net "NC_U219_NC1")
		)
		(pad "2" smd rect
			(at -1.199896 0 270)
			(size 0.5588 0.8128)
			(layers "F.Cu" "F.Mask" "F.Paste")
			(net "OCP_V3_2_WAKE_BUFF_R_N")
		)
		(pad "3" smd rect
			(at -1.199896 0.94996 270)
			(size 0.5588 0.8128)
			(layers "F.Cu" "F.Mask" "F.Paste")
			(net "GND")
		)
		(pad "4" smd rect
			(at 1.199896 0.94996 270)
			(size 0.5588 0.8128)
			(layers "F.Cu" "F.Mask" "F.Paste")
			(net "IRQ_LVC3_V3_2_WAKE_BUF_N")
		)
		(pad "5" smd rect
			(at 1.199896 -0.94996 270)
			(size 0.5588 0.8128)
			(layers "F.Cu" "F.Mask" "F.Paste")
			(net "P3V3_AUX")
		)
	)
	(footprint ""
		(layer "F.Cu")
		(at 369.190778 -391.797286 180)
		(property "Reference" "R4166"
			(at 0 0 180)
			(layer "F.SilkS")
			(hide yes)
			(effects
				(font
					(size 1.27 1.27)
				)
			)
		)
		(property "Value" ""
			(at 0 0 180)
			(layer "F.Fab")
			(effects
				(font
					(size 1.27 1.27)
				)
			)
		)
		(duplicate_pad_numbers_are_jumpers no)
		(fp_line
			(start 0.7874 0.4064)
			(end -0.7874 0.4064)
			(stroke
				(width 0.1524)
				(type default)
			)
			(layer "F.SilkS")
		)
		(fp_line
			(start 0.7874 -0.4064)
			(end 0.7874 0.4064)
			(stroke
				(width 0.1524)
				(type default)
			)
			(layer "F.SilkS")
		)
		(fp_line
			(start -0.7874 0.4064)
			(end -0.7874 -0.4064)
			(stroke
				(width 0.1524)
				(type default)
			)
			(layer "F.SilkS")
		)
		(fp_line
			(start -0.7874 -0.4064)
			(end 0.7874 -0.4064)
			(stroke
				(width 0.1524)
				(type default)
			)
			(layer "F.SilkS")
		)
		(fp_line
			(start 0.67945 0.3048)
			(end 0.120396 0.3048)
			(stroke
				(width 0.1)
				(type default)
			)
			(layer "F.Fab")
		)
		(fp_line
			(start 0.67945 -0.3048)
			(end 0.67945 0.3048)
			(stroke
				(width 0.1)
				(type default)
			)
			(layer "F.Fab")
		)
		(fp_line
			(start 0.12065 -0.2794)
			(end 0.12065 -0.3048)
			(stroke
				(width 0.1)
				(type default)
			)
			(layer "F.Fab")
		)
		(fp_line
			(start 0.12065 -0.3048)
			(end 0.67945 -0.3048)
			(stroke
				(width 0.1)
				(type default)
			)
			(layer "F.Fab")
		)
		(fp_line
			(start 0.120396 0.3048)
			(end 0.120396 0.2794)
			(stroke
				(width 0.1)
				(type default)
			)
			(layer "F.Fab")
		)
		(fp_line
			(start 0.120396 0.2794)
			(end -0.12065 0.2794)
			(stroke
				(width 0.1)
				(type default)
			)
			(layer "F.Fab")
		)
		(fp_line
			(start -0.12065 0.3048)
			(end -0.67945 0.3048)
			(stroke
				(width 0.1)
				(type default)
			)
			(layer "F.Fab")
		)
		(fp_line
			(start -0.12065 0.2794)
			(end -0.12065 0.3048)
			(stroke
				(width 0.1)
				(type default)
			)
			(layer "F.Fab")
		)
		(fp_line
			(start -0.12065 -0.2794)
			(end 0.12065 -0.2794)
			(stroke
				(width 0.1)
				(type default)
			)
			(layer "F.Fab")
		)
		(fp_line
			(start -0.12065 -0.305054)
			(end -0.12065 -0.2794)
			(stroke
				(width 0.1)
				(type default)
			)
			(layer "F.Fab")
		)
		(fp_line
			(start -0.67945 0.3048)
			(end -0.67945 -0.305054)
			(stroke
				(width 0.1)
				(type default)
			)
			(layer "F.Fab")
		)
		(fp_line
			(start -0.67945 -0.305054)
			(end -0.12065 -0.305054)
			(stroke
				(width 0.1)
				(type default)
			)
			(layer "F.Fab")
		)
		(pad "1" smd circle
			(at -0.40005 0 180)
			(size 0 0)
			(layers "F.Cu" "F.Mask" "F.Paste")
			(net "P3V3_AUX")
		)
		(pad "2" smd circle
			(at 0.40005 0 180)
			(size 0 0)
			(layers "F.Cu" "F.Mask" "F.Paste")
			(net "GPU_3V3IO_RSVD3_N")
		)
	)
)
